(kicad_pcb
	(version 20260206)
	(generator "pcbnew")
	(generator_version "10.0")
	(general
		(thickness 1.6)
		(legacy_teardrops no)
	)
	(paper "A4")
	(title_block
		(title "Wiwynn_Tioga_Pass_MB.brd")
		(comment 1 "Tioga Pass / footprints 2940-2946 of 4770")
	)
	(layers
		(0 "F.Cu" signal "TOP")
		(4 "In1.Cu" signal "L2GND")
		(6 "In2.Cu" signal "L3")
		(8 "In3.Cu" signal "L4GND")
		(10 "In4.Cu" signal "L5")
		(12 "In5.Cu" signal "L6GND")
		(14 "In6.Cu" signal "L7VCC")
		(16 "In7.Cu" signal "L8VCC")
		(18 "In8.Cu" signal "L9GND")
		(20 "In9.Cu" signal "L10")
		(22 "In10.Cu" signal "L11GND")
		(24 "In11.Cu" signal "L12")
		(26 "In12.Cu" signal "L13GND")
		(2 "B.Cu" signal "BOTTOM")
		(9 "F.Adhes" user "F.Adhesive")
		(11 "B.Adhes" user "B.Adhesive")
		(13 "F.Paste" user "Package Geometry/Pastemask Top")
		(15 "B.Paste" user "Package Geometry/Pastemask Bottom")
		(5 "F.SilkS" user "Ref Des/Silkscreen Top")
		(7 "B.SilkS" user "Ref Des/Silkscreen Bottom")
		(1 "F.Mask" user "Board Geometry/Soldermask Top")
		(3 "B.Mask" user "Board Geometry/Soldermask Bottom")
		(17 "Dwgs.User" user "User.Drawings")
		(19 "Cmts.User" user "User.Comments")
		(21 "Eco1.User" user "User.Eco1")
		(23 "Eco2.User" user "User.Eco2")
		(25 "Edge.Cuts" user "Board Geometry/Outline")
		(27 "Margin" user)
		(31 "F.CrtYd" user "Package Geometry/Place Bound Top")
		(29 "B.CrtYd" user "Package Geometry/Place Bound Bottom")
		(35 "F.Fab" user "Ref Des/Assembly Top")
		(33 "B.Fab" user "Ref Des/Assembly Bottom")
	)
	(footprint ""
		(layer "B.Cu")
		(at 168.088818 -73.653396 180)
		(property "Reference" "R4W6"
			(at 0.8382 -0.67818 180)
			(unlocked yes)
			(layer "B.SilkS")
			(effects
				(font
					(size 0.4064 0.254)
					(thickness 0.1524)
				)
				(justify left mirror)
			)
		)
		(property "Value" ""
			(at 0 0 0)
			(layer "B.Fab")
			(effects
				(font
					(size 1.27 1.27)
				)
				(justify mirror)
			)
		)
		(duplicate_pad_numbers_are_jumpers no)
		(fp_poly
			(pts
				(xy 0.2794 -0.1016) (xy -0.2794 -0.1016) (xy -0.2794 0.9906) (xy 0.2794 0.9906)
			)
			(stroke
				(width 0)
				(type default)
			)
			(fill no)
			(layer "B.CrtYd")
		)
		(fp_line
			(start 0.2794 0.9906)
			(end -0.2794 0.9906)
			(stroke
				(width 0.1)
				(type default)
			)
			(layer "B.Fab")
		)
		(fp_line
			(start 0.2794 -0.1016)
			(end 0.2794 0.9906)
			(stroke
				(width 0.1)
				(type default)
			)
			(layer "B.Fab")
		)
		(fp_line
			(start -0.2794 0.9906)
			(end -0.2794 -0.1016)
			(stroke
				(width 0.1)
				(type default)
			)
			(layer "B.Fab")
		)
		(fp_line
			(start -0.2794 -0.1016)
			(end 0.2794 -0.1016)
			(stroke
				(width 0.1)
				(type default)
			)
			(layer "B.Fab")
		)
		(pad "1" smd rect
			(at 0 0)
			(size 0.508 0.508)
			(layers "B.Cu" "B.Mask" "B.Paste")
			(net "P3V3_DB1200")
		)
		(pad "2" smd rect
			(at 0 0.889)
			(size 0.508 0.508)
			(layers "B.Cu" "B.Mask" "B.Paste")
			(net "FM_DB1200_PWRGD_R")
		)
		(zone
			(layer "B.Cu")
			(hatch none 0.5)
			(connect_pads
				(clearance 0)
			)
			(min_thickness 0.25)
			(keepout
				(tracks not_allowed)
				(vias allowed)
				(pads allowed)
				(copperpour not_allowed)
				(footprints allowed)
			)
			(placement
				(enabled no)
				(sheetname "")
			)
			(fill
				(thermal_gap 0.5)
				(thermal_bridge_width 0.5)
				(island_removal_mode 0)
			)
			(polygon
				(pts
					(xy 167.834818 -74.288396) (xy 168.342818 -74.288396) (xy 168.342818 -73.907396) (xy 167.834818 -73.907396)
				)
			)
		)
		(zone
			(layer "B.Cu")
			(hatch none 0.5)
			(connect_pads
				(clearance 0)
			)
			(min_thickness 0.25)
			(keepout
				(tracks allowed)
				(vias not_allowed)
				(pads allowed)
				(copperpour not_allowed)
				(footprints allowed)
			)
			(placement
				(enabled no)
				(sheetname "")
			)
			(fill
				(thermal_gap 0.5)
				(thermal_bridge_width 0.5)
				(island_removal_mode 0)
			)
			(polygon
				(pts
					(xy 167.834818 -73.907396) (xy 168.342818 -73.907396) (xy 168.342818 -74.288396) (xy 167.834818 -74.288396)
				)
			)
		)
	)
	(footprint ""
		(layer "B.Cu")
		(at -0.6604 -137.7696)
		(property "Reference" "CT8"
			(at 0.8382 -0.84963 0)
			(unlocked yes)
			(layer "B.SilkS")
			(effects
				(font
					(size 0.7874 0.5842)
					(thickness 0.1524)
				)
				(justify left mirror)
			)
		)
		(property "Value" ""
			(at 0 0 0)
			(layer "B.Fab")
			(effects
				(font
					(size 1.27 1.27)
				)
				(justify mirror)
			)
		)
		(duplicate_pad_numbers_are_jumpers no)
		(fp_poly
			(pts
				(xy -0.3048 -0.1016) (xy -0.3048 0.9906) (xy 0.3048 0.9906) (xy 0.3048 -0.1016)
			)
			(stroke
				(width 0)
				(type default)
			)
			(fill no)
			(layer "B.CrtYd")
		)
		(fp_line
			(start -0.3048 -0.1016)
			(end 0.3048 -0.1016)
			(stroke
				(width 0.1)
				(type default)
			)
			(layer "B.Fab")
		)
		(fp_line
			(start -0.3048 0.9906)
			(end -0.3048 -0.1016)
			(stroke
				(width 0.1)
				(type default)
			)
			(layer "B.Fab")
		)
		(fp_line
			(start 0.3048 -0.1016)
			(end 0.3048 0.9906)
			(stroke
				(width 0.1)
				(type default)
			)
			(layer "B.Fab")
		)
		(fp_line
			(start 0.3048 0.9906)
			(end -0.3048 0.9906)
			(stroke
				(width 0.1)
				(type default)
			)
			(layer "B.Fab")
		)
		(pad "1" smd rect
			(at 0 0 180)
			(size 0.508 0.508)
			(layers "B.Cu" "B.Mask" "B.Paste")
			(net "A_TSENSE_PVDDQ_KLM")
		)
		(pad "2" smd rect
			(at 0 0.889 180)
			(size 0.508 0.508)
			(layers "B.Cu" "B.Mask" "B.Paste")
			(net "GND")
		)
		(zone
			(layer "B.Cu")
			(hatch none 0.5)
			(connect_pads
				(clearance 0)
			)
			(min_thickness 0.25)
			(keepout
				(tracks allowed)
				(vias not_allowed)
				(pads allowed)
				(copperpour not_allowed)
				(footprints allowed)
			)
			(placement
				(enabled no)
				(sheetname "")
			)
			(fill
				(thermal_gap 0.5)
				(thermal_bridge_width 0.5)
				(island_removal_mode 0)
			)
			(polygon
				(pts
					(xy -0.4064 -137.5156) (xy -0.9144 -137.5156) (xy -0.9144 -137.1346) (xy -0.4064 -137.1346)
				)
			)
		)
		(zone
			(layer "B.Cu")
			(hatch none 0.5)
			(connect_pads
				(clearance 0)
			)
			(min_thickness 0.25)
			(keepout
				(tracks not_allowed)
				(vias allowed)
				(pads allowed)
				(copperpour not_allowed)
				(footprints allowed)
			)
			(placement
				(enabled no)
				(sheetname "")
			)
			(fill
				(thermal_gap 0.5)
				(thermal_bridge_width 0.5)
				(island_removal_mode 0)
			)
			(polygon
				(pts
					(xy -0.4064 -137.1346) (xy -0.9144 -137.1346) (xy -0.9144 -137.5156) (xy -0.4064 -137.5156)
				)
			)
		)
	)
	(footprint ""
		(layer "B.Cu")
		(at 340.3092 -86.4362)
		(property "Reference" "R3P17"
			(at 0 0 0)
			(layer "B.SilkS")
			(hide yes)
			(effects
				(font
					(size 1.27 1.27)
				)
				(justify mirror)
			)
		)
		(property "Value" ""
			(at 0 0 0)
			(layer "B.Fab")
			(effects
				(font
					(size 1.27 1.27)
				)
				(justify mirror)
			)
		)
		(duplicate_pad_numbers_are_jumpers no)
		(fp_poly
			(pts
				(xy 0.2794 -0.1016) (xy -0.2794 -0.1016) (xy -0.2794 0.9906) (xy 0.2794 0.9906)
			)
			(stroke
				(width 0)
				(type default)
			)
			(fill no)
			(layer "B.CrtYd")
		)
		(fp_line
			(start -0.2794 -0.1016)
			(end 0.2794 -0.1016)
			(stroke
				(width 0.1)
				(type default)
			)
			(layer "B.Fab")
		)
		(fp_line
			(start -0.2794 0.9906)
			(end -0.2794 -0.1016)
			(stroke
				(width 0.1)
				(type default)
			)
			(layer "B.Fab")
		)
		(fp_line
			(start 0.2794 -0.1016)
			(end 0.2794 0.9906)
			(stroke
				(width 0.1)
				(type default)
			)
			(layer "B.Fab")
		)
		(fp_line
			(start 0.2794 0.9906)
			(end -0.2794 0.9906)
			(stroke
				(width 0.1)
				(type default)
			)
			(layer "B.Fab")
		)
		(pad "1" smd rect
			(at 0 0 180)
			(size 0.508 0.508)
			(layers "B.Cu" "B.Mask" "B.Paste")
			(net "PVCCIO_CPU0")
		)
		(pad "2" smd rect
			(at 0 0.889 180)
			(size 0.508 0.508)
			(layers "B.Cu" "B.Mask" "B.Paste")
			(net "SVID_CLK0_CPU0_R")
		)
		(zone
			(layer "B.Cu")
			(hatch none 0.5)
			(connect_pads
				(clearance 0)
			)
			(min_thickness 0.25)
			(keepout
				(tracks allowed)
				(vias not_allowed)
				(pads allowed)
				(copperpour not_allowed)
				(footprints allowed)
			)
			(placement
				(enabled no)
				(sheetname "")
			)
			(fill
				(thermal_gap 0.5)
				(thermal_bridge_width 0.5)
				(island_removal_mode 0)
			)
			(polygon
				(pts
					(xy 340.5632 -86.1822) (xy 340.0552 -86.1822) (xy 340.0552 -85.8012) (xy 340.5632 -85.8012)
				)
			)
		)
		(zone
			(layer "B.Cu")
			(hatch none 0.5)
			(connect_pads
				(clearance 0)
			)
			(min_thickness 0.25)
			(keepout
				(tracks not_allowed)
				(vias allowed)
				(pads allowed)
				(copperpour not_allowed)
				(footprints allowed)
			)
			(placement
				(enabled no)
				(sheetname "")
			)
			(fill
				(thermal_gap 0.5)
				(thermal_bridge_width 0.5)
				(island_removal_mode 0)
			)
			(polygon
				(pts
					(xy 340.5632 -85.8012) (xy 340.0552 -85.8012) (xy 340.0552 -86.1822) (xy 340.5632 -86.1822)
				)
			)
		)
	)
	(footprint ""
		(layer "B.Cu")
		(at 378.5362 -5.7658 -90)
		(property "Reference" "CR3U1"
			(at -1.6764 0.1524 0)
			(unlocked yes)
			(layer "B.SilkS")
			(effects
				(font
					(size 0.4064 0.254)
					(thickness 0.1524)
				)
				(justify left mirror)
			)
		)
		(property "Value" ""
			(at 0 0 90)
			(layer "B.Fab")
			(effects
				(font
					(size 1.27 1.27)
				)
				(justify mirror)
			)
		)
		(duplicate_pad_numbers_are_jumpers no)
		(fp_line
			(start -0.9144 2.9464)
			(end -0.8382 2.9464)
			(stroke
				(width 0.1524)
				(type default)
			)
			(layer "B.SilkS")
		)
		(fp_line
			(start 0.9144 2.9464)
			(end 0.8382 2.9464)
			(stroke
				(width 0.1524)
				(type default)
			)
			(layer "B.SilkS")
		)
		(fp_line
			(start -0.9144 0.1016)
			(end -0.9144 2.9464)
			(stroke
				(width 0.1524)
				(type default)
			)
			(layer "B.SilkS")
		)
		(fp_line
			(start -0.8382 0.1016)
			(end -0.9144 0.1016)
			(stroke
				(width 0.1524)
				(type default)
			)
			(layer "B.SilkS")
		)
		(fp_line
			(start 0.8382 0.1016)
			(end 0.9144 0.1016)
			(stroke
				(width 0.1524)
				(type default)
			)
			(layer "B.SilkS")
		)
		(fp_line
			(start 0.9144 0.1016)
			(end 0.9144 2.9464)
			(stroke
				(width 0.1524)
				(type default)
			)
			(layer "B.SilkS")
		)
		(fp_circle
			(center -1.128776 -0.907288)
			(end -1.128776 -1.034288)
			(stroke
				(width 0.254)
				(type default)
			)
			(fill no)
			(layer "B.SilkS")
		)
		(fp_poly
			(pts
				(xy 0 0.1016) (xy -0.5334 0.1016) (xy -0.7366 0.1016) (xy -0.9144 0.1016) (xy -0.9144 2.9464) (xy -0.8382 2.9464)
				(xy -0.762 2.9464) (xy 0.9144 2.9464) (xy 0.9144 2.7686) (xy 0.9144 2.159) (xy 0.9144 0.1016) (xy 0.7366 0.1016)
				(xy 0.5842 0.1016)
			)
			(stroke
				(width 0)
				(type default)
			)
			(fill no)
			(layer "B.CrtYd")
		)
		(fp_line
			(start -0.9144 2.9464)
			(end -0.9144 0.1016)
			(stroke
				(width 0.1)
				(type default)
			)
			(layer "B.Fab")
		)
		(fp_line
			(start 0.9144 2.9464)
			(end -0.9144 2.9464)
			(stroke
				(width 0.1)
				(type default)
			)
			(layer "B.Fab")
		)
		(fp_line
			(start -0.9144 0.1016)
			(end 0.9144 0.1016)
			(stroke
				(width 0.1)
				(type default)
			)
			(layer "B.Fab")
		)
		(fp_line
			(start 0.9144 0.1016)
			(end 0.9144 2.9464)
			(stroke
				(width 0.1)
				(type default)
			)
			(layer "B.Fab")
		)
		(fp_circle
			(center -1.128776 -0.907288)
			(end -1.128776 -1.034288)
			(stroke
				(width 0.254)
				(type default)
			)
			(fill no)
			(layer "B.Fab")
		)
		(pad "1" smd rect
			(at 0 0 180)
			(size 1.524 0.762)
			(layers "B.Cu" "B.Mask" "B.Paste")
			(net "P3V3_STBY_PLD_D")
		)
		(pad "2" smd rect
			(at 0 3.048)
			(size 1.524 0.762)
			(layers "B.Cu" "B.Mask" "B.Paste")
			(net "P3V3_STBY")
		)
	)
	(footprint ""
		(layer "B.Cu")
		(at 410.464 -153.162 90)
		(property "Reference" "C2L9"
			(at 0 0 90)
			(layer "B.SilkS")
			(hide yes)
			(effects
				(font
					(size 1.27 1.27)
				)
				(justify mirror)
			)
		)
		(property "Value" ""
			(at 0 0 90)
			(layer "B.Fab")
			(effects
				(font
					(size 1.27 1.27)
				)
				(justify mirror)
			)
		)
		(duplicate_pad_numbers_are_jumpers no)
		(fp_poly
			(pts
				(xy -0.3048 -0.1016) (xy -0.3048 0.9906) (xy 0.3048 0.9906) (xy 0.3048 -0.1016)
			)
			(stroke
				(width 0)
				(type default)
			)
			(fill no)
			(layer "B.CrtYd")
		)
		(fp_line
			(start 0.3048 -0.1016)
			(end 0.3048 0.9906)
			(stroke
				(width 0.1)
				(type default)
			)
			(layer "B.Fab")
		)
		(fp_line
			(start -0.3048 -0.1016)
			(end 0.3048 -0.1016)
			(stroke
				(width 0.1)
				(type default)
			)
			(layer "B.Fab")
		)
		(fp_line
			(start 0.3048 0.9906)
			(end -0.3048 0.9906)
			(stroke
				(width 0.1)
				(type default)
			)
			(layer "B.Fab")
		)
		(fp_line
			(start -0.3048 0.9906)
			(end -0.3048 -0.1016)
			(stroke
				(width 0.1)
				(type default)
			)
			(layer "B.Fab")
		)
		(pad "1" smd rect
			(at 0 0 270)
			(size 0.508 0.508)
			(layers "B.Cu" "B.Mask" "B.Paste")
			(net "SATA6G_PCH_PCIE_UP_SATA_RXN<5>")
		)
		(pad "2" smd rect
			(at 0 0.889 270)
			(size 0.508 0.508)
			(layers "B.Cu" "B.Mask" "B.Paste")
			(net "SATA6G_P5_RX_C_DN")
		)
		(zone
			(layer "B.Cu")
			(hatch none 0.5)
			(connect_pads
				(clearance 0)
			)
			(min_thickness 0.25)
			(keepout
				(tracks allowed)
				(vias not_allowed)
				(pads allowed)
				(copperpour not_allowed)
				(footprints allowed)
			)
			(placement
				(enabled no)
				(sheetname "")
			)
			(fill
				(thermal_gap 0.5)
				(thermal_bridge_width 0.5)
				(island_removal_mode 0)
			)
			(polygon
				(pts
					(xy 410.718 -153.416) (xy 410.718 -152.908) (xy 411.099 -152.908) (xy 411.099 -153.416)
				)
			)
		)
		(zone
			(layer "B.Cu")
			(hatch none 0.5)
			(connect_pads
				(clearance 0)
			)
			(min_thickness 0.25)
			(keepout
				(tracks not_allowed)
				(vias allowed)
				(pads allowed)
				(copperpour not_allowed)
				(footprints allowed)
			)
			(placement
				(enabled no)
				(sheetname "")
			)
			(fill
				(thermal_gap 0.5)
				(thermal_bridge_width 0.5)
				(island_removal_mode 0)
			)
			(polygon
				(pts
					(xy 411.099 -153.416) (xy 411.099 -152.908) (xy 410.718 -152.908) (xy 410.718 -153.416)
				)
			)
		)
	)
	(footprint ""
		(layer "B.Cu")
		(at 312.786268 -31.69285)
		(property "Reference" "R8D30"
			(at 0 0 0)
			(layer "B.SilkS")
			(hide yes)
			(effects
				(font
					(size 1.27 1.27)
				)
				(justify mirror)
			)
		)
		(property "Value" ""
			(at 0 0 0)
			(layer "B.Fab")
			(effects
				(font
					(size 1.27 1.27)
				)
				(justify mirror)
			)
		)
		(duplicate_pad_numbers_are_jumpers no)
		(fp_poly
			(pts
				(xy 0.2794 -0.1016) (xy -0.2794 -0.1016) (xy -0.2794 0.9906) (xy 0.2794 0.9906)
			)
			(stroke
				(width 0)
				(type default)
			)
			(fill no)
			(layer "B.CrtYd")
		)
		(fp_line
			(start -0.2794 -0.1016)
			(end 0.2794 -0.1016)
			(stroke
				(width 0.1)
				(type default)
			)
			(layer "B.Fab")
		)
		(fp_line
			(start -0.2794 0.9906)
			(end -0.2794 -0.1016)
			(stroke
				(width 0.1)
				(type default)
			)
			(layer "B.Fab")
		)
		(fp_line
			(start 0.2794 -0.1016)
			(end 0.2794 0.9906)
			(stroke
				(width 0.1)
				(type default)
			)
			(layer "B.Fab")
		)
		(fp_line
			(start 0.2794 0.9906)
			(end -0.2794 0.9906)
			(stroke
				(width 0.1)
				(type default)
			)
			(layer "B.Fab")
		)
		(pad "1" smd rect
			(at 0 0 180)
			(size 0.508 0.508)
			(layers "B.Cu" "B.Mask" "B.Paste")
			(net "IRQ_DIMM_SAVE_N")
		)
		(pad "2" smd rect
			(at 0 0.889 180)
			(size 0.508 0.508)
			(layers "B.Cu" "B.Mask" "B.Paste")
			(net "IRQ_DIMM_SAVE_R_N")
		)
		(zone
			(layer "B.Cu")
			(hatch none 0.5)
			(connect_pads
				(clearance 0)
			)
			(min_thickness 0.25)
			(keepout
				(tracks allowed)
				(vias not_allowed)
				(pads allowed)
				(copperpour not_allowed)
				(footprints allowed)
			)
			(placement
				(enabled no)
				(sheetname "")
			)
			(fill
				(thermal_gap 0.5)
				(thermal_bridge_width 0.5)
				(island_removal_mode 0)
			)
			(polygon
				(pts
					(xy 313.040268 -31.43885) (xy 312.532268 -31.43885) (xy 312.532268 -31.05785) (xy 313.040268 -31.05785)
				)
			)
		)
		(zone
			(layer "B.Cu")
			(hatch none 0.5)
			(connect_pads
				(clearance 0)
			)
			(min_thickness 0.25)
			(keepout
				(tracks not_allowed)
				(vias allowed)
				(pads allowed)
				(copperpour not_allowed)
				(footprints allowed)
			)
			(placement
				(enabled no)
				(sheetname "")
			)
			(fill
				(thermal_gap 0.5)
				(thermal_bridge_width 0.5)
				(island_removal_mode 0)
			)
			(polygon
				(pts
					(xy 313.040268 -31.05785) (xy 312.532268 -31.05785) (xy 312.532268 -31.43885) (xy 313.040268 -31.43885)
				)
			)
		)
	)
	(footprint ""
		(layer "B.Cu")
		(at 391.65022 -153.46172 -90)
		(property "Reference" "C4W3"
			(at 0.8382 -0.67818 270)
			(unlocked yes)
			(layer "B.SilkS")
			(effects
				(font
					(size 0.4064 0.254)
					(thickness 0.1524)
				)
				(justify left mirror)
			)
		)
		(property "Value" ""
			(at 0 0 90)
			(layer "B.Fab")
			(effects
				(font
					(size 1.27 1.27)
				)
				(justify mirror)
			)
		)
		(duplicate_pad_numbers_are_jumpers no)
		(fp_poly
			(pts
				(xy -0.3048 -0.1016) (xy -0.3048 0.9906) (xy 0.3048 0.9906) (xy 0.3048 -0.1016)
			)
			(stroke
				(width 0)
				(type default)
			)
			(fill no)
			(layer "B.CrtYd")
		)
		(fp_line
			(start -0.3048 0.9906)
			(end -0.3048 -0.1016)
			(stroke
				(width 0.1)
				(type default)
			)
			(layer "B.Fab")
		)
		(fp_line
			(start 0.3048 0.9906)
			(end -0.3048 0.9906)
			(stroke
				(width 0.1)
				(type default)
			)
			(layer "B.Fab")
		)
		(fp_line
			(start -0.3048 -0.1016)
			(end 0.3048 -0.1016)
			(stroke
				(width 0.1)
				(type default)
			)
			(layer "B.Fab")
		)
		(fp_line
			(start 0.3048 -0.1016)
			(end 0.3048 0.9906)
			(stroke
				(width 0.1)
				(type default)
			)
			(layer "B.Fab")
		)
		(pad "1" smd rect
			(at 0 0 90)
			(size 0.508 0.508)
			(layers "B.Cu" "B.Mask" "B.Paste")
			(net "A_TSENSE_PVNN_PCH_TMON")
		)
		(pad "2" smd rect
			(at 0 0.889 90)
			(size 0.508 0.508)
			(layers "B.Cu" "B.Mask" "B.Paste")
			(net "GND")
		)
		(zone
			(layer "B.Cu")
			(hatch none 0.5)
			(connect_pads
				(clearance 0)
			)
			(min_thickness 0.25)
			(keepout
				(tracks not_allowed)
				(vias allowed)
				(pads allowed)
				(copperpour not_allowed)
				(footprints allowed)
			)
			(placement
				(enabled no)
				(sheetname "")
			)
			(fill
				(thermal_gap 0.5)
				(thermal_bridge_width 0.5)
				(island_removal_mode 0)
			)
			(polygon
				(pts
					(xy 391.01522 -153.20772) (xy 391.01522 -153.71572) (xy 391.39622 -153.71572) (xy 391.39622 -153.20772)
				)
			)
		)
		(zone
			(layer "B.Cu")
			(hatch none 0.5)
			(connect_pads
				(clearance 0)
			)
			(min_thickness 0.25)
			(keepout
				(tracks allowed)
				(vias not_allowed)
				(pads allowed)
				(copperpour not_allowed)
				(footprints allowed)
			)
			(placement
				(enabled no)
				(sheetname "")
			)
			(fill
				(thermal_gap 0.5)
				(thermal_bridge_width 0.5)
				(island_removal_mode 0)
			)
			(polygon
				(pts
					(xy 391.39622 -153.20772) (xy 391.39622 -153.71572) (xy 391.01522 -153.71572) (xy 391.01522 -153.20772)
				)
			)
		)
	)
)
